# T6G (Grand Teton) — schematic netlist excerpt (pin names and nets, part order shuffled) for the footprints in the layout excerpt that follows; sources: Cadence DE-HDL packaged netlist, KiCad conversion of 04192023_DAF0TMB3IC0_F0TG_MB_C_brd_V02_OCP.brd

PC494  Q_CAPP  220UF 4V 20% SPCAP  pkg SMLF  page 194 : A = PVDDCR_CPU0_P0 ; B = GND
C2365  Q_CAP  22UF 4V 20% X6S  pkg C0402  page 73 : A = PVDDCR_CPU1_P1 ; B = GND
C536  Q_CAP  10UF 25V 10% X6S  pkg C0805  page 107 : A = P12V_MEM_CPU1 ; B = GND

(kicad_pcb
	(version 20260206)
	(generator "pcbnew")
	(generator_version "10.0")
	(general
		(thickness 1.6)
		(legacy_teardrops no)
	)
	(paper "A4")
	(title_block
		(title "04192023_DAF0TMB3IC0_F0TG_MB_C_brd_V02_OCP.brd")
		(comment 1 "Grand Teton / footprints 5798-5800 of 8354")
	)
	(layers
		(0 "F.Cu" signal "TOP")
		(4 "In1.Cu" signal "GND")
		(6 "In2.Cu" signal "IN1")
		(8 "In3.Cu" signal "GND1")
		(10 "In4.Cu" signal "IN2")
		(12 "In5.Cu" signal "GND2")
		(14 "In6.Cu" signal "IN3")
		(16 "In7.Cu" signal "GND3")
		(18 "In8.Cu" signal "VCC")
		(20 "In9.Cu" signal "VCC1")
		(22 "In10.Cu" signal "GND4")
		(24 "In11.Cu" signal "IN4")
		(26 "In12.Cu" signal "GND5")
		(28 "In13.Cu" signal "IN5")
		(30 "In14.Cu" signal "GND6")
		(32 "In15.Cu" signal "IN6")
		(34 "In16.Cu" signal "GND7")
		(2 "B.Cu" signal "BOTTOM")
		(9 "F.Adhes" user "F.Adhesive")
		(11 "B.Adhes" user "B.Adhesive")
		(13 "F.Paste" user "Package Geometry/Pastemask Top")
		(15 "B.Paste" user "Package Geometry/Pastemask Bottom")
		(5 "F.SilkS" user "Ref Des/Silkscreen Top")
		(7 "B.SilkS" user "Ref Des/Silkscreen Bottom")
		(1 "F.Mask" user "Board Geometry/Soldermask Top")
		(3 "B.Mask" user "Board Geometry/Soldermask Bottom")
		(17 "Dwgs.User" user "User.Drawings")
		(19 "Cmts.User" user "User.Comments")
		(21 "Eco1.User" user "User.Eco1")
		(23 "Eco2.User" user "User.Eco2")
		(25 "Edge.Cuts" user "Board Geometry/Outline")
		(27 "Margin" user)
		(31 "F.CrtYd" user "Package Geometry/Place Bound Top")
		(29 "B.CrtYd" user "Package Geometry/Place Bound Bottom")
		(35 "F.Fab" user "Ref Des/Assembly Top")
		(33 "B.Fab" user "Ref Des/Assembly Bottom")
	)
	(footprint ""
		(layer "B.Cu")
		(at 116.880386 -269.307564)
		(property "Reference" "C2365"
			(at 0 0 0)
			(layer "B.SilkS")
			(hide yes)
			(effects
				(font
					(size 1.27 1.27)
				)
				(justify mirror)
			)
		)
		(property "Value" ""
			(at 0 0 0)
			(layer "B.Fab")
			(effects
				(font
					(size 1.27 1.27)
				)
				(justify mirror)
			)
		)
		(duplicate_pad_numbers_are_jumpers no)
		(fp_line
			(start -0.7874 -0.4064)
			(end -0.7874 0.4064)
			(stroke
				(width 0.1524)
				(type default)
			)
			(layer "B.SilkS")
		)
		(fp_line
			(start -0.7874 0.4064)
			(end 0.7874 0.4064)
			(stroke
				(width 0.1524)
				(type default)
			)
			(layer "B.SilkS")
		)
		(fp_line
			(start 0.7874 -0.4064)
			(end -0.7874 -0.4064)
			(stroke
				(width 0.1524)
				(type default)
			)
			(layer "B.SilkS")
		)
		(fp_line
			(start 0.7874 0.4064)
			(end 0.7874 -0.4064)
			(stroke
				(width 0.1524)
				(type default)
			)
			(layer "B.SilkS")
		)
		(fp_line
			(start -0.67945 -0.3048)
			(end -0.67945 0.3048)
			(stroke
				(width 0.1)
				(type default)
			)
			(layer "B.Fab")
		)
		(fp_line
			(start -0.67945 0.3048)
			(end -0.120396 0.3048)
			(stroke
				(width 0.1)
				(type default)
			)
			(layer "B.Fab")
		)
		(fp_line
			(start -0.12065 -0.3048)
			(end -0.67945 -0.3048)
			(stroke
				(width 0.1)
				(type default)
			)
			(layer "B.Fab")
		)
		(fp_line
			(start -0.12065 -0.2794)
			(end -0.12065 -0.3048)
			(stroke
				(width 0.1)
				(type default)
			)
			(layer "B.Fab")
		)
		(fp_line
			(start -0.120396 0.2794)
			(end 0.12065 0.2794)
			(stroke
				(width 0.1)
				(type default)
			)
			(layer "B.Fab")
		)
		(fp_line
			(start -0.120396 0.3048)
			(end -0.120396 0.2794)
			(stroke
				(width 0.1)
				(type default)
			)
			(layer "B.Fab")
		)
		(fp_line
			(start 0.12065 -0.305054)
			(end 0.12065 -0.2794)
			(stroke
				(width 0.1)
				(type default)
			)
			(layer "B.Fab")
		)
		(fp_line
			(start 0.12065 -0.2794)
			(end -0.12065 -0.2794)
			(stroke
				(width 0.1)
				(type default)
			)
			(layer "B.Fab")
		)
		(fp_line
			(start 0.12065 0.2794)
			(end 0.12065 0.3048)
			(stroke
				(width 0.1)
				(type default)
			)
			(layer "B.Fab")
		)
		(fp_line
			(start 0.12065 0.3048)
			(end 0.67945 0.3048)
			(stroke
				(width 0.1)
				(type default)
			)
			(layer "B.Fab")
		)
		(fp_line
			(start 0.67945 -0.305054)
			(end 0.12065 -0.305054)
			(stroke
				(width 0.1)
				(type default)
			)
			(layer "B.Fab")
		)
		(fp_line
			(start 0.67945 0.3048)
			(end 0.67945 -0.305054)
			(stroke
				(width 0.1)
				(type default)
			)
			(layer "B.Fab")
		)
		(pad "1" smd circle
			(at 0.40005 0 180)
			(size 0 0)
			(layers "B.Cu" "B.Mask" "B.Paste")
			(net "PVDDCR_CPU1_P1")
		)
		(pad "2" smd circle
			(at -0.40005 0 180)
			(size 0 0)
			(layers "B.Cu" "B.Mask" "B.Paste")
			(net "GND")
		)
	)
	(footprint ""
		(layer "B.Cu")
		(at 365.064294 -184.48909 90)
		(property "Reference" "PC494"
			(at 5.894324 -1.181862 270)
			(unlocked yes)
			(layer "B.SilkS")
			(effects
				(font
					(size 0.7874 0.5842)
					(thickness 0.1524)
				)
				(justify left mirror)
			)
		)
		(property "Value" ""
			(at 0 0 90)
			(layer "B.Fab")
			(effects
				(font
					(size 1.27 1.27)
				)
				(justify mirror)
			)
		)
		(duplicate_pad_numbers_are_jumpers no)
		(fp_line
			(start 4.533392 -2.249932)
			(end -4.533392 -2.249932)
			(stroke
				(width 0.1524)
				(type default)
			)
			(layer "B.SilkS")
		)
		(fp_line
			(start -4.533392 -2.249932)
			(end -4.533392 2.249932)
			(stroke
				(width 0.1524)
				(type default)
			)
			(layer "B.SilkS")
		)
		(fp_line
			(start 4.533392 2.249932)
			(end 4.533392 -2.249932)
			(stroke
				(width 0.1524)
				(type default)
			)
			(layer "B.SilkS")
		)
		(fp_line
			(start -4.533392 2.249932)
			(end 4.533392 2.249932)
			(stroke
				(width 0.1524)
				(type default)
			)
			(layer "B.SilkS")
		)
		(fp_rect
			(start 4.533392 -2.326132)
			(end 5.39242 2.326132)
			(stroke
				(width 0)
				(type default)
			)
			(fill yes)
			(layer "B.SilkS")
		)
		(fp_line
			(start 3.750056 -2.249932)
			(end -3.750056 -2.249932)
			(stroke
				(width 0.1)
				(type default)
			)
			(layer "B.Fab")
		)
		(fp_line
			(start -3.750056 -2.249932)
			(end -3.750056 2.249932)
			(stroke
				(width 0.1)
				(type default)
			)
			(layer "B.Fab")
		)
		(fp_line
			(start 3.750056 2.249932)
			(end 3.750056 -2.249932)
			(stroke
				(width 0.1)
				(type default)
			)
			(layer "B.Fab")
		)
		(fp_line
			(start -3.750056 2.249932)
			(end 3.750056 2.249932)
			(stroke
				(width 0.1)
				(type default)
			)
			(layer "B.Fab")
		)
		(fp_text user "-"
			(at -4.8514 -0.14605 90)
			(unlocked yes)
			(layer "B.SilkS")
			(effects
				(font
					(size 1.905 1.4224)
					(thickness 0.1524)
				)
				(justify left mirror)
			)
		)
		(fp_text user "+"
			(at 6.322314 0.786384 0)
			(unlocked yes)
			(layer "B.SilkS")
			(effects
				(font
					(size 1.905 1.4224)
					(thickness 0.1524)
				)
				(justify left mirror)
			)
		)
		(fp_text user "-"
			(at -4.8514 -0.14605 90)
			(unlocked yes)
			(layer "B.Fab")
			(effects
				(font
					(size 1.905 1.4224)
					(thickness 0.1524)
				)
				(justify left mirror)
			)
		)
		(fp_text user "+"
			(at 6.322314 0.786384 0)
			(unlocked yes)
			(layer "B.Fab")
			(effects
				(font
					(size 1.905 1.4224)
					(thickness 0.1524)
				)
				(justify left mirror)
			)
		)
		(pad "1" smd rect
			(at 3.199892 0 270)
			(size 2.413 2.8194)
			(layers "B.Cu" "B.Mask" "B.Paste")
			(net "PVDDCR_CPU0_P0")
		)
		(pad "2" smd rect
			(at -3.199892 0 270)
			(size 2.413 2.8194)
			(layers "B.Cu" "B.Mask" "B.Paste")
			(net "GND")
		)
	)
	(footprint ""
		(layer "B.Cu")
		(at 191.160146 -192.66027)
		(property "Reference" "C536"
			(at 0 0 0)
			(layer "B.SilkS")
			(hide yes)
			(effects
				(font
					(size 1.27 1.27)
				)
				(justify mirror)
			)
		)
		(property "Value" ""
			(at 0 0 0)
			(layer "B.Fab")
			(effects
				(font
					(size 1.27 1.27)
				)
				(justify mirror)
			)
		)
		(duplicate_pad_numbers_are_jumpers no)
		(fp_line
			(start -1.524 -0.762)
			(end -1.524 0.762)
			(stroke
				(width 0.1524)
				(type default)
			)
			(layer "B.SilkS")
		)
		(fp_line
			(start -1.524 0.762)
			(end 1.524 0.762)
			(stroke
				(width 0.1524)
				(type default)
			)
			(layer "B.SilkS")
		)
		(fp_line
			(start 1.524 -0.762)
			(end -1.524 -0.762)
			(stroke
				(width 0.1524)
				(type default)
			)
			(layer "B.SilkS")
		)
		(fp_line
			(start 1.524 0.762)
			(end 1.524 -0.762)
			(stroke
				(width 0.1524)
				(type default)
			)
			(layer "B.SilkS")
		)
		(fp_line
			(start -1.1049 -0.724916)
			(end 1.1049 -0.724916)
			(stroke
				(width 0.1)
				(type default)
			)
			(layer "B.Fab")
		)
		(fp_line
			(start -1.1049 0.724916)
			(end -1.1049 -0.724916)
			(stroke
				(width 0.1)
				(type default)
			)
			(layer "B.Fab")
		)
		(fp_line
			(start 1.1049 -0.724916)
			(end 1.1049 0.724916)
			(stroke
				(width 0.1)
				(type default)
			)
			(layer "B.Fab")
		)
		(fp_line
			(start 1.1049 0.724916)
			(end -1.1049 0.724916)
			(stroke
				(width 0.1)
				(type default)
			)
			(layer "B.Fab")
		)
		(pad "1" smd rect
			(at 0.889 0)
			(size 1.016 1.27)
			(layers "B.Cu" "B.Mask" "B.Paste")
			(net "P12V_MEM_CPU1")
		)
		(pad "2" smd rect
			(at -0.889 0)
			(size 1.016 1.27)
			(layers "B.Cu" "B.Mask" "B.Paste")
			(net "GND")
		)
	)
)
